# SCM (Grand Teton) — schematic netlist excerpt (pin names and nets, part order shuffled) for the footprints in the layout excerpt that follows; sources: Cadence DE-HDL packaged netlist, KiCad conversion of 12092022_DA0F0TMDCD0_F0T_Management_Board_D_brd_V3_OCP.brd

D10  DIODE_BIDIRECTIONAL  UCLAMP0511T IC  pkg SLP1006P2T  page 50 : A = REAR_AC_PWR_BTN ; C = GND
C26  Q_CAP  0.1UF 25V 10% X7R  pkg 0402  page 15 : A = P3V3_AUX ; B = GND

(kicad_pcb
	(version 20260206)
	(generator "pcbnew")
	(generator_version "10.0")
	(general
		(thickness 1.6)
		(legacy_teardrops no)
	)
	(paper "A4")
	(title_block
		(title "12092022_DA0F0TMDCD0_F0T_Management_Board_D_brd_V3_OCP.brd")
		(comment 1 "Grand Teton / footprints 180-181 of 1440")
	)
	(layers
		(0 "F.Cu" signal "TOP")
		(4 "In1.Cu" signal "GND")
		(6 "In2.Cu" signal "IN1")
		(8 "In3.Cu" signal "GND1")
		(10 "In4.Cu" signal "IN2")
		(12 "In5.Cu" signal "VCC")
		(14 "In6.Cu" signal "VCC1")
		(16 "In7.Cu" signal "IN3")
		(18 "In8.Cu" signal "GND2")
		(20 "In9.Cu" signal "IN4")
		(22 "In10.Cu" signal "GND3")
		(2 "B.Cu" signal "BOTTOM")
		(9 "F.Adhes" user "F.Adhesive")
		(11 "B.Adhes" user "B.Adhesive")
		(13 "F.Paste" user "Package Geometry/Pastemask Top")
		(15 "B.Paste" user "Package Geometry/Pastemask Bottom")
		(5 "F.SilkS" user "Ref Des/Silkscreen Top")
		(7 "B.SilkS" user "Ref Des/Silkscreen Bottom")
		(1 "F.Mask" user "Board Geometry/Soldermask Top")
		(3 "B.Mask" user "Board Geometry/Soldermask Bottom")
		(17 "Dwgs.User" user "User.Drawings")
		(19 "Cmts.User" user "User.Comments")
		(21 "Eco1.User" user "User.Eco1")
		(23 "Eco2.User" user "User.Eco2")
		(25 "Edge.Cuts" user "Board Geometry/Outline")
		(27 "Margin" user)
		(31 "F.CrtYd" user "Package Geometry/Place Bound Top")
		(29 "B.CrtYd" user "Package Geometry/Place Bound Bottom")
		(35 "F.Fab" user "Ref Des/Assembly Top")
		(33 "B.Fab" user "Ref Des/Assembly Bottom")
	)
	(footprint ""
		(layer "F.Cu")
		(at 75.032108 -11.061954 90)
		(property "Reference" "D10"
			(at -1.029716 1.187704 90)
			(unlocked yes)
			(layer "F.SilkS")
			(effects
				(font
					(size 0.7874 0.5842)
					(thickness 0.1524)
				)
				(justify left)
			)
		)
		(property "Value" ""
			(at 0 0 90)
			(layer "F.Fab")
			(effects
				(font
					(size 1.27 1.27)
				)
			)
		)
		(duplicate_pad_numbers_are_jumpers no)
		(fp_line
			(start 0.94488 -0.450088)
			(end -0.854964 -0.450088)
			(stroke
				(width 0.1524)
				(type default)
			)
			(layer "F.SilkS")
		)
		(fp_line
			(start -0.854964 -0.450088)
			(end -0.854964 0.450088)
			(stroke
				(width 0.1524)
				(type default)
			)
			(layer "F.SilkS")
		)
		(fp_line
			(start 0.870458 -0.2794)
			(end 0.845058 0.4064)
			(stroke
				(width 0.1524)
				(type default)
			)
			(layer "F.SilkS")
		)
		(fp_line
			(start 0.845058 0.4064)
			(end 0.845058 -0.381)
			(stroke
				(width 0.1524)
				(type default)
			)
			(layer "F.SilkS")
		)
		(fp_line
			(start 0.94488 0.450088)
			(end 0.94488 -0.450088)
			(stroke
				(width 0.1524)
				(type default)
			)
			(layer "F.SilkS")
		)
		(fp_line
			(start -0.854964 0.450088)
			(end 0.925068 0.450088)
			(stroke
				(width 0.1524)
				(type default)
			)
			(layer "F.SilkS")
		)
		(fp_line
			(start 0.54991 -0.350012)
			(end -0.54991 -0.350012)
			(stroke
				(width 0.1)
				(type default)
			)
			(layer "F.Fab")
		)
		(fp_line
			(start -0.54991 -0.350012)
			(end -0.54991 0.350012)
			(stroke
				(width 0.1)
				(type default)
			)
			(layer "F.Fab")
		)
		(fp_line
			(start 0.54991 0.350012)
			(end 0.54991 -0.350012)
			(stroke
				(width 0.1)
				(type default)
			)
			(layer "F.Fab")
		)
		(fp_line
			(start -0.54991 0.350012)
			(end 0.54991 0.350012)
			(stroke
				(width 0.1)
				(type default)
			)
			(layer "F.Fab")
		)
		(fp_text user "+"
			(at -0.808228 0.239014 270)
			(unlocked yes)
			(layer "F.SilkS")
			(effects
				(font
					(size 1.905 1.4224)
					(thickness 0.1524)
				)
				(justify left)
			)
		)
		(fp_text user "-"
			(at 2.196846 0.577342 270)
			(unlocked yes)
			(layer "F.SilkS")
			(effects
				(font
					(size 1.905 1.4224)
					(thickness 0.1524)
				)
				(justify left)
			)
		)
		(fp_text user "-"
			(at 2.48539 0.239014 270)
			(unlocked yes)
			(layer "F.Fab")
			(effects
				(font
					(size 1.905 1.4224)
					(thickness 0.1524)
				)
				(justify left)
			)
		)
		(fp_text user "+"
			(at -0.808228 0.239014 270)
			(unlocked yes)
			(layer "F.Fab")
			(effects
				(font
					(size 1.905 1.4224)
					(thickness 0.1524)
				)
				(justify left)
			)
		)
		(pad "A" smd rect
			(at -0.424942 0 90)
			(size 0.5588 0.6096)
			(layers "F.Cu" "F.Mask" "F.Paste")
			(net "REAR_AC_PWR_BTN")
		)
		(pad "C" smd rect
			(at 0.424942 0 270)
			(size 0.5588 0.6096)
			(layers "F.Cu" "F.Mask" "F.Paste")
			(net "GND")
		)
	)
	(footprint ""
		(layer "F.Cu")
		(at 39.37 -73.914 90)
		(property "Reference" "C26"
			(at 0 0 90)
			(layer "F.SilkS")
			(hide yes)
			(effects
				(font
					(size 1.27 1.27)
				)
			)
		)
		(property "Value" ""
			(at 0 0 90)
			(layer "F.Fab")
			(effects
				(font
					(size 1.27 1.27)
				)
			)
		)
		(duplicate_pad_numbers_are_jumpers no)
		(fp_line
			(start 0.7874 -0.4064)
			(end 0.7874 0.141986)
			(stroke
				(width 0.1524)
				(type default)
			)
			(layer "F.SilkS")
		)
		(fp_line
			(start -0.7874 -0.4064)
			(end 0.7874 -0.4064)
			(stroke
				(width 0.1524)
				(type default)
			)
			(layer "F.SilkS")
		)
		(fp_line
			(start -0.7874 0.070866)
			(end -0.7874 -0.4064)
			(stroke
				(width 0.1524)
				(type default)
			)
			(layer "F.SilkS")
		)
		(fp_line
			(start 0.413004 0.4064)
			(end -0.440436 0.4064)
			(stroke
				(width 0.1524)
				(type default)
			)
			(layer "F.SilkS")
		)
		(fp_line
			(start -0.12065 -0.305054)
			(end -0.12065 -0.2794)
			(stroke
				(width 0.1)
				(type default)
			)
			(layer "F.Fab")
		)
		(fp_line
			(start -0.67945 -0.305054)
			(end -0.12065 -0.305054)
			(stroke
				(width 0.1)
				(type default)
			)
			(layer "F.Fab")
		)
		(fp_line
			(start 0.67945 -0.3048)
			(end 0.67945 0.3048)
			(stroke
				(width 0.1)
				(type default)
			)
			(layer "F.Fab")
		)
		(fp_line
			(start 0.12065 -0.3048)
			(end 0.67945 -0.3048)
			(stroke
				(width 0.1)
				(type default)
			)
			(layer "F.Fab")
		)
		(fp_line
			(start 0.12065 -0.2794)
			(end 0.12065 -0.3048)
			(stroke
				(width 0.1)
				(type default)
			)
			(layer "F.Fab")
		)
		(fp_line
			(start -0.12065 -0.2794)
			(end 0.12065 -0.2794)
			(stroke
				(width 0.1)
				(type default)
			)
			(layer "F.Fab")
		)
		(fp_line
			(start 0.120396 0.2794)
			(end -0.12065 0.2794)
			(stroke
				(width 0.1)
				(type default)
			)
			(layer "F.Fab")
		)
		(fp_line
			(start -0.12065 0.2794)
			(end -0.12065 0.3048)
			(stroke
				(width 0.1)
				(type default)
			)
			(layer "F.Fab")
		)
		(fp_line
			(start 0.67945 0.3048)
			(end 0.120396 0.3048)
			(stroke
				(width 0.1)
				(type default)
			)
			(layer "F.Fab")
		)
		(fp_line
			(start 0.120396 0.3048)
			(end 0.120396 0.2794)
			(stroke
				(width 0.1)
				(type default)
			)
			(layer "F.Fab")
		)
		(fp_line
			(start -0.12065 0.3048)
			(end -0.67945 0.3048)
			(stroke
				(width 0.1)
				(type default)
			)
			(layer "F.Fab")
		)
		(fp_line
			(start -0.67945 0.3048)
			(end -0.67945 -0.305054)
			(stroke
				(width 0.1)
				(type default)
			)
			(layer "F.Fab")
		)
		(pad "1" smd circle
			(at -0.40005 0 90)
			(size 0 0)
			(layers "F.Cu" "F.Mask" "F.Paste")
			(net "P3V3_AUX")
		)
		(pad "2" smd circle
			(at 0.40005 0 90)
			(size 0 0)
			(layers "F.Cu" "F.Mask" "F.Paste")
			(net "GND")
		)
	)
)
